(kicad_pcb
	(version 20260206)
	(generator "pcbnew")
	(generator_version "10.0")
	(general
		(thickness 1.21888)
		(legacy_teardrops no)
	)
	(paper "A4")
	(title_block
		(title "timecard-v8 — TimeCard-DC-V8_EXP.PcbDoc")
		(comment 1 "Time Appliance Project (Time Card) / footprints 1-6 of 288")
	)
	(layers
		(0 "F.Cu" signal "TOP")
		(4 "In1.Cu" signal "SGND")
		(6 "In2.Cu" signal "IN1")
		(8 "In3.Cu" signal "IN2")
		(10 "In4.Cu" signal "SGND1")
		(2 "B.Cu" signal "BOTTOM")
		(9 "F.Adhes" user "F.Adhesive")
		(11 "B.Adhes" user "B.Adhesive")
		(13 "F.Paste" user "Top Paste")
		(15 "B.Paste" user "Bottom Paste")
		(5 "F.SilkS" user "Top Overlay")
		(7 "B.SilkS" user "Bottom Overlay")
		(1 "F.Mask" user "Top Solder")
		(3 "B.Mask" user "Bottom Solder")
		(17 "Dwgs.User" user "User.Drawings")
		(19 "Cmts.User" user "User.Comments")
		(21 "Eco1.User" user "User.Eco1")
		(23 "Eco2.User" user "User.Eco2")
		(25 "Edge.Cuts" user)
		(27 "Margin" user)
		(31 "F.CrtYd" user "Top Courtyard")
		(29 "B.CrtYd" user "Bottom Courtyard")
		(35 "F.Fab" user "Top Component Center")
		(33 "B.Fab" user "Bottom Component Center")
	)
	(footprint "Vault:RESC3216X89X64NL25T25"
		(layer "F.Cu")
		(at 209.6261 92.0162 90)
		(property "Reference" "R7"
			(at 3.7 -0.393345 270)
			(unlocked yes)
			(layer "F.SilkS")
			(effects
				(font
					(size 0.762 0.762)
					(thickness 0.2286)
				)
				(justify left bottom)
			)
		)
		(property "Value" "2mOhm_1%_1206"
			(at -8.378245 7.6471 0)
			(unlocked yes)
			(layer "F.SilkS")
			(hide yes)
			(effects
				(font
					(size 0.762 0.762)
					(thickness 0.2286)
				)
				(justify left bottom)
			)
		)
		(sheetname "POWER")
		(sheetfile "POWER.kicad_sch")
		(duplicate_pad_numbers_are_jumpers no)
		(fp_line
			(start -0.2 -0.825)
			(end 0.2 -0.825)
			(stroke
				(width 0.2)
				(type solid)
			)
			(layer "F.SilkS")
		)
		(fp_line
			(start -0.2 0.825)
			(end 0.2 0.825)
			(stroke
				(width 0.2)
				(type solid)
			)
			(layer "F.SilkS")
		)
		(pad "1" smd rect
			(at -1.325 0 180)
			(size 1.85 1.5)
			(layers "F.Cu" "F.Mask" "F.Paste")
			(net "+12V_SENS")
		)
		(pad "2" smd rect
			(at 1.325 0 180)
			(size 1.85 1.5)
			(layers "F.Cu" "F.Mask" "F.Paste")
			(net "+12V")
		)
	)
	(footprint "Vault:FP-ERJ2RK-IPC_A"
		(layer "F.Cu")
		(at 167.19755 85.03403 -90)
		(property "Reference" "R95"
			(at 0.05357 1.744519 90)
			(unlocked yes)
			(layer "F.SilkS")
			(effects
				(font
					(size 0.762 0.762)
					(thickness 0.2286)
				)
			)
		)
		(property "Value" "200_1%_0402"
			(at -2.935471 7.782475 180)
			(unlocked yes)
			(layer "F.SilkS")
			(hide yes)
			(effects
				(font
					(size 0.762 0.762)
					(thickness 0.2286)
				)
			)
		)
		(sheetname "USBUart_DipSelects")
		(sheetfile "USBUart_DipSelects.kicad_sch")
		(duplicate_pad_numbers_are_jumpers no)
		(fp_line
			(start 0.83624 0.73624)
			(end -0.83624 0.73624)
			(stroke
				(width 0.2)
				(type solid)
			)
			(layer "F.SilkS")
		)
		(fp_line
			(start 0.83624 -0.73624)
			(end -0.83624 -0.73624)
			(stroke
				(width 0.2)
				(type solid)
			)
			(layer "F.SilkS")
		)
		(fp_line
			(start -1.03624 0.53624)
			(end -1.03624 -0.53624)
			(stroke
				(width 0.2)
				(type solid)
			)
			(layer "F.CrtYd")
		)
		(fp_line
			(start 1.03624 0.53624)
			(end -1.03624 0.53624)
			(stroke
				(width 0.2)
				(type solid)
			)
			(layer "F.CrtYd")
		)
		(fp_line
			(start 1.03624 0.53624)
			(end 1.03624 -0.53624)
			(stroke
				(width 0.2)
				(type solid)
			)
			(layer "F.CrtYd")
		)
		(fp_line
			(start 1.03624 -0.53624)
			(end -1.03624 -0.53624)
			(stroke
				(width 0.2)
				(type solid)
			)
			(layer "F.CrtYd")
		)
		(fp_line
			(start -1.03624 0.53624)
			(end -1.03624 -0.53624)
			(stroke
				(width 0.2)
				(type solid)
			)
			(layer "F.Fab")
		)
		(fp_line
			(start 1.03624 0.53624)
			(end -1.03624 0.53624)
			(stroke
				(width 0.2)
				(type solid)
			)
			(layer "F.Fab")
		)
		(fp_line
			(start 1.03624 0.53624)
			(end 1.03624 -0.53624)
			(stroke
				(width 0.2)
				(type solid)
			)
			(layer "F.Fab")
		)
		(fp_line
			(start 0 0.5)
			(end 0 -0.5)
			(stroke
				(width 0.1)
				(type solid)
			)
			(layer "F.Fab")
		)
		(fp_line
			(start 0.5 0)
			(end -0.5 0)
			(stroke
				(width 0.1)
				(type solid)
			)
			(layer "F.Fab")
		)
		(fp_line
			(start 1.03624 -0.53624)
			(end -1.03624 -0.53624)
			(stroke
				(width 0.2)
				(type solid)
			)
			(layer "F.Fab")
		)
		(fp_text user "${REFERENCE}"
			(at -0.00001 0.09602 270)
			(unlocked yes)
			(layer "F.Fab")
			(effects
				(font
					(face "Arial")
					(size 0.63 0.63)
					(thickness 0.1)
				)
				(justify left bottom)
			)
		)
		(pad "1" smd rect
			(at -0.50215 0 270)
			(size 0.66818 0.67248)
			(layers "F.Cu" "F.Mask" "F.Paste")
			(net "DIP_SW_UART_SEL")
			(solder_mask_margin 0)
			(solder_paste_margin 0)
		)
		(pad "2" smd rect
			(at 0.50215 0 270)
			(size 0.66818 0.67248)
			(layers "F.Cu" "F.Mask" "F.Paste")
			(net "NetD25_1")
			(solder_mask_margin 0)
			(solder_paste_margin 0)
		)
	)
	(footprint "Vault:RESC0402(1005)_N"
		(layer "F.Cu")
		(at 205.5261 127.9162)
		(property "Reference" "R70"
			(at 0.1286 3.026931 0)
			(unlocked yes)
			(layer "F.SilkS")
			(effects
				(font
					(size 0.762 0.762)
					(thickness 0.2286)
				)
			)
		)
		(property "Value" "1.21_1%_0402"
			(at -2.783081 8.468145 270)
			(unlocked yes)
			(layer "F.SilkS")
			(hide yes)
			(effects
				(font
					(size 0.762 0.762)
					(thickness 0.2286)
				)
			)
		)
		(sheetname "POWER")
		(sheetfile "POWER.kicad_sch")
		(duplicate_pad_numbers_are_jumpers no)
		(pad "1" smd rect
			(at -0.5 0 90)
			(size 0.65 0.55)
			(layers "F.Cu" "F.Mask" "F.Paste")
			(net "P3V3_VDD")
		)
		(pad "2" smd rect
			(at 0.5 0 90)
			(size 0.65 0.55)
			(layers "F.Cu" "F.Mask" "F.Paste")
			(net "P3V3_PVDD")
		)
	)
	(footprint "Vault:FP-39-30-0040-MFG"
		(layer "F.Cu")
		(at 234.1699 89.5827 90)
		(property "Reference" "J38"
			(at 5.373155 -10.4438 0)
			(unlocked yes)
			(layer "F.SilkS")
			(effects
				(font
					(size 0.762 0.762)
					(thickness 0.2286)
				)
				(justify left bottom)
			)
		)
		(property "Value" "39-30-0040"
			(at -20.802445 -1.5141 0)
			(unlocked yes)
			(layer "F.SilkS")
			(hide yes)
			(effects
				(font
					(size 0.762 0.762)
					(thickness 0.2286)
				)
				(justify left bottom)
			)
		)
		(sheetname "POWER")
		(sheetfile "POWER.kicad_sch")
		(duplicate_pad_numbers_are_jumpers no)
		(fp_line
			(start 5.0165 -6.35)
			(end 5.0165 6.731)
			(stroke
				(width 0.2)
				(type solid)
			)
			(layer "F.SilkS")
		)
		(fp_line
			(start 3.84549 -6.35)
			(end 5.0165 -6.35)
			(stroke
				(width 0.2)
				(type solid)
			)
			(layer "F.SilkS")
		)
		(fp_line
			(start -0.34551 -6.35)
			(end 0.3455 -6.35)
			(stroke
				(width 0.2)
				(type solid)
			)
			(layer "F.SilkS")
		)
		(fp_line
			(start -5.0165 -6.35)
			(end -3.8455 -6.35)
			(stroke
				(width 0.2)
				(type solid)
			)
			(layer "F.SilkS")
		)
		(fp_line
			(start -5.0165 -6.35)
			(end -5.0165 6.731)
			(stroke
				(width 0.2)
				(type solid)
			)
			(layer "F.SilkS")
		)
		(fp_line
			(start -5.0165 6.731)
			(end 5.0165 6.731)
			(stroke
				(width 0.2)
				(type solid)
			)
			(layer "F.SilkS")
		)
		(fp_circle
			(center 5.61649 -7.5438)
			(end 5.74149 -7.5438)
			(stroke
				(width 0.25)
				(type solid)
			)
			(fill no)
			(layer "F.SilkS")
		)
		(fp_line
			(start 5.1165 -14.5306)
			(end 5.1165 6.831)
			(stroke
				(width 0.2)
				(type solid)
			)
			(layer "F.CrtYd")
		)
		(fp_line
			(start -5.1165 -14.5306)
			(end 5.1165 -14.5306)
			(stroke
				(width 0.2)
				(type solid)
			)
			(layer "F.CrtYd")
		)
		(fp_line
			(start -5.1165 -14.5306)
			(end -5.1165 6.831)
			(stroke
				(width 0.2)
				(type solid)
			)
			(layer "F.CrtYd")
		)
		(fp_line
			(start -5.1165 6.831)
			(end 5.1165 6.831)
			(stroke
				(width 0.2)
				(type solid)
			)
			(layer "F.CrtYd")
		)
		(fp_line
			(start 5.1165 -14.5306)
			(end 5.1165 6.831)
			(stroke
				(width 0.2)
				(type solid)
			)
			(layer "F.Fab")
		)
		(fp_line
			(start -5.1165 -14.5306)
			(end 5.1165 -14.5306)
			(stroke
				(width 0.2)
				(type solid)
			)
			(layer "F.Fab")
		)
		(fp_line
			(start -5.1165 -14.5306)
			(end -5.1165 6.831)
			(stroke
				(width 0.2)
				(type solid)
			)
			(layer "F.Fab")
		)
		(fp_line
			(start 0 -0.5)
			(end 0 0.5)
			(stroke
				(width 0.1)
				(type solid)
			)
			(layer "F.Fab")
		)
		(fp_line
			(start -0.5 0)
			(end 0.49999 0)
			(stroke
				(width 0.1)
				(type solid)
			)
			(layer "F.Fab")
		)
		(fp_line
			(start -5.1165 6.831)
			(end 5.1165 6.831)
			(stroke
				(width 0.2)
				(type solid)
			)
			(layer "F.Fab")
		)
		(fp_text user "${REFERENCE}"
			(at -0.00186 -3.56555 90)
			(unlocked yes)
			(layer "F.Fab")
			(effects
				(font
					(face "Arial")
					(size 0.63 0.63)
					(thickness 0.1)
				)
				(justify left bottom)
			)
		)
		(pad "" np_thru_hole circle
			(at 0 -0.254 90)
			(size 2.9972 2.9972)
			(drill 2.9972)
			(layers "*.Cu" "*.Mask")
			(solder_mask_margin 0)
			(solder_paste_margin -1000)
			(thermal_bridge_angle 90)
		)
		(pad "1" thru_hole rect
			(at 2.0955 -7.5438 90)
			(size 2.75 2.75)
			(drill 1.8)
			(layers "*.Cu" "*.Mask")
			(remove_unused_layers no)
			(net "GND")
			(solder_mask_margin 0)
			(solder_paste_margin -1000)
		)
		(pad "2" thru_hole circle
			(at -2.0955 -7.5438 90)
			(size 2.75 2.75)
			(drill 1.8)
			(layers "*.Cu" "*.Mask")
			(remove_unused_layers no)
			(net "GND")
			(solder_mask_margin 0)
			(solder_paste_margin -1000)
			(thermal_bridge_angle 90)
		)
		(pad "3" thru_hole circle
			(at 2.0955 -13.0556 90)
			(size 2.75 2.75)
			(drill 1.8)
			(layers "*.Cu" "*.Mask")
			(remove_unused_layers no)
			(net "NetD12_2")
			(solder_mask_margin 0)
			(solder_paste_margin -1000)
			(thermal_bridge_angle 90)
		)
		(pad "4" thru_hole circle
			(at -2.0955 -13.0556 90)
			(size 2.75 2.75)
			(drill 1.8)
			(layers "*.Cu" "*.Mask")
			(remove_unused_layers no)
			(net "NetD12_2")
			(solder_mask_margin 0)
			(solder_paste_margin -1000)
			(thermal_bridge_angle 90)
		)
	)
	(footprint "Vault:RESC1005X40X25LL05T05"
		(layer "F.Cu")
		(at 80.3261 84.0162)
		(property "Reference" "R108"
			(at -2.8714 0.226931 0)
			(unlocked yes)
			(layer "F.SilkS")
			(effects
				(font
					(size 0.762 0.762)
					(thickness 0.2286)
				)
			)
		)
		(property "Value" "4.7K_0402"
			(at -2.352802 6.563805 270)
			(unlocked yes)
			(layer "F.SilkS")
			(hide yes)
			(effects
				(font
					(size 1.524 1.524)
					(thickness 0.254)
				)
			)
		)
		(sheetname "USER_IO_STATUS")
		(sheetfile "USER_IO_STATUS.kicad_sch")
		(duplicate_pad_numbers_are_jumpers no)
		(pad "1" smd rect
			(at -0.4 0 90)
			(size 0.45 0.45)
			(layers "F.Cu" "F.Mask" "F.Paste")
			(net "+3.3V")
		)
		(pad "2" smd rect
			(at 0.4 0 90)
			(size 0.45 0.45)
			(layers "F.Cu" "F.Mask" "F.Paste")
			(net "NetR108_2")
		)
	)
	(footprint "GNSS:GNSS Header 16-pin"
		(layer "F.Cu")
		(at 229.84861 58.1786 180)
		(property "Reference" "J13"
			(at 5.19391 1.735479 0)
			(unlocked yes)
			(layer "F.SilkS")
			(effects
				(font
					(size 0.762 0.762)
					(thickness 0.2286)
				)
			)
		)
		(property "Value" "GNSS Header 16-pin"
			(at 6.740175 4.840511 180)
			(unlocked yes)
			(layer "F.SilkS")
			(hide yes)
			(effects
				(font
					(size 0.762 0.762)
					(thickness 0.2286)
				)
			)
		)
		(sheetname "GPS_IMU_SENSORS")
		(sheetfile "GPS_IMU_SENSORS.kicad_sch")
		(duplicate_pad_numbers_are_jumpers no)
		(fp_line
			(start 8.50001 0.5)
			(end -0.49999 0.5)
			(stroke
				(width 0.0254)
				(type solid)
			)
			(layer "F.SilkS")
		)
		(fp_line
			(start 8.50001 -7.5)
			(end 8.50001 0.5)
			(stroke
				(width 0.0254)
				(type solid)
			)
			(layer "F.SilkS")
		)
		(fp_line
			(start 8.50001 -7.5)
			(end -0.49999 -7.5)
			(stroke
				(width 0.0254)
				(type solid)
			)
			(layer "F.SilkS")
		)
		(fp_line
			(start -0.49999 -7.5)
			(end -0.49999 0.5)
			(stroke
				(width 0.0254)
				(type solid)
			)
			(layer "F.SilkS")
		)
		(fp_circle
			(center 0 -0.5)
			(end 0 -0.4746)
			(stroke
				(width 0.508)
				(type solid)
			)
			(fill no)
			(layer "F.SilkS")
		)
		(fp_text user "Orig 2x4"
			(at 8.011685 -6.109 90)
			(unlocked yes)
			(layer "F.SilkS")
			(effects
				(font
					(size 0.762 0.762)
					(thickness 0.2286)
				)
				(justify left bottom)
			)
		)
		(pad "0" thru_hole circle
			(at 4.00001 -13.49998 90)
			(size 0 0)
			(drill 0.76)
			(layers "*.Cu" "*.Mask")
			(remove_unused_layers no)
			(thermal_bridge_angle 90)
		)
		(pad "0" thru_hole circle
			(at 4.00001 -1.5 90)
			(size 0 0)
			(drill 0.76)
			(layers "*.Cu" "*.Mask")
			(remove_unused_layers no)
			(thermal_bridge_angle 90)
		)
		(pad "1" smd rect
			(at 1.77751 -0.5 90)
			(size 1.12 2.105)
			(layers "F.Cu" "F.Mask" "F.Paste")
			(net "+5.0V")
		)
		(pad "2" smd rect
			(at 6.22251 -0.5 90)
			(size 1.12 2.105)
			(layers "F.Cu" "F.Mask" "F.Paste")
			(net "+3.3V")
		)
		(pad "3" smd rect
			(at 1.77751 -2.5 90)
			(size 1.12 2.105)
			(layers "F.Cu" "F.Mask" "F.Paste")
			(net "GPS2_TX")
		)
		(pad "4" smd rect
			(at 6.22251 -2.5 90)
			(size 1.12 2.105)
			(layers "F.Cu" "F.Mask" "F.Paste")
			(net "GPS2_RST")
		)
		(pad "5" smd rect
			(at 1.77751 -4.5 90)
			(size 1.12 2.105)
			(layers "F.Cu" "F.Mask" "F.Paste")
			(net "GPS2_RX")
		)
		(pad "6" smd rect
			(at 6.22251 -4.5 90)
			(size 1.12 2.105)
			(layers "F.Cu" "F.Mask" "F.Paste")
			(net "GPS2_TP1")
		)
		(pad "7" smd rect
			(at 1.77751 -6.5 90)
			(size 1.12 2.105)
			(layers "F.Cu" "F.Mask" "F.Paste")
			(net "GPS2_TP2")
		)
		(pad "8" smd rect
			(at 6.22251 -6.5 90)
			(size 1.12 2.105)
			(layers "F.Cu" "F.Mask" "F.Paste")
			(net "GND")
		)
		(pad "9" smd rect
			(at 1.77751 -8.50001 90)
			(size 1.12 2.105)
			(layers "F.Cu" "F.Mask" "F.Paste")
			(net "+5.0V")
		)
		(pad "10" smd rect
			(at 6.22251 -8.50001 90)
			(size 1.12 2.105)
			(layers "F.Cu" "F.Mask" "F.Paste")
			(net "+3.3V")
		)
		(pad "11" smd rect
			(at 1.77751 -10.50001 90)
			(size 1.12 2.105)
			(layers "F.Cu" "F.Mask" "F.Paste")
			(net "GPS2_PIN11")
		)
		(pad "12" smd rect
			(at 6.22251 -10.50001 90)
			(size 1.12 2.105)
			(layers "F.Cu" "F.Mask" "F.Paste")
			(net "GPS2_PIN12")
		)
		(pad "13" smd rect
			(at 1.77751 -12.5 90)
			(size 1.12 2.105)
			(layers "F.Cu" "F.Mask" "F.Paste")
			(net "GPS2_PIN13")
		)
		(pad "14" smd rect
			(at 6.22251 -12.5 90)
			(size 1.12 2.105)
			(layers "F.Cu" "F.Mask" "F.Paste")
			(net "GPS2_PIN14")
		)
		(pad "15" smd rect
			(at 1.77751 -14.5 90)
			(size 1.12 2.105)
			(layers "F.Cu" "F.Mask" "F.Paste")
			(net "GPS2_PIN15")
		)
		(pad "16" smd rect
			(at 6.22251 -14.5 90)
			(size 1.12 2.105)
			(layers "F.Cu" "F.Mask" "F.Paste")
			(net "GND")
		)
	)
)
